# BASEBOARD_FAB2 (Tioga Pass) — schematic netlist excerpt (pin names and nets, part order shuffled) for the footprints in the layout excerpt that follows; sources: Cadence DE-HDL packaged netlist, KiCad conversion of Wiwynn_Tioga_Pass_MB.brd

C7D5  CAP_A  0.1UF 16V 10% X7R  pkg 0402V  page 92 : A = P0V7_GTL2104_VREF_0 ; B = GND
R4E17  RES  0.0 5% CHIP  pkg 0402  page 204 : A = VSENSE_PVCCIN_CPU0_N ; B = VSENSE_PVCCIN_CPU0_SKT_VRTN
R8E13  RES  33.2 1% CHIP  pkg 0402  page 184 : A = SPI_PCH_MISO ; B = SPI_PCH_TPM_MISO_R

(kicad_pcb
	(version 20260206)
	(generator "pcbnew")
	(generator_version "10.0")
	(general
		(thickness 1.6)
		(legacy_teardrops no)
	)
	(paper "A4")
	(title_block
		(title "Wiwynn_Tioga_Pass_MB.brd")
		(comment 1 "Tioga Pass / footprints 797-799 of 4770")
	)
	(layers
		(0 "F.Cu" signal "TOP")
		(4 "In1.Cu" signal "L2GND")
		(6 "In2.Cu" signal "L3")
		(8 "In3.Cu" signal "L4GND")
		(10 "In4.Cu" signal "L5")
		(12 "In5.Cu" signal "L6GND")
		(14 "In6.Cu" signal "L7VCC")
		(16 "In7.Cu" signal "L8VCC")
		(18 "In8.Cu" signal "L9GND")
		(20 "In9.Cu" signal "L10")
		(22 "In10.Cu" signal "L11GND")
		(24 "In11.Cu" signal "L12")
		(26 "In12.Cu" signal "L13GND")
		(2 "B.Cu" signal "BOTTOM")
		(9 "F.Adhes" user "F.Adhesive")
		(11 "B.Adhes" user "B.Adhesive")
		(13 "F.Paste" user "Package Geometry/Pastemask Top")
		(15 "B.Paste" user "Package Geometry/Pastemask Bottom")
		(5 "F.SilkS" user "Ref Des/Silkscreen Top")
		(7 "B.SilkS" user "Ref Des/Silkscreen Bottom")
		(1 "F.Mask" user "Board Geometry/Soldermask Top")
		(3 "B.Mask" user "Board Geometry/Soldermask Bottom")
		(17 "Dwgs.User" user "User.Drawings")
		(19 "Cmts.User" user "User.Comments")
		(21 "Eco1.User" user "User.Eco1")
		(23 "Eco2.User" user "User.Eco2")
		(25 "Edge.Cuts" user "Board Geometry/Outline")
		(27 "Margin" user)
		(31 "F.CrtYd" user "Package Geometry/Place Bound Top")
		(29 "B.CrtYd" user "Package Geometry/Place Bound Bottom")
		(35 "F.Fab" user "Ref Des/Assembly Top")
		(33 "B.Fab" user "Ref Des/Assembly Bottom")
	)
	(footprint ""
		(layer "F.Cu")
		(at 406.9461 -62.611 90)
		(property "Reference" "R8E13"
			(at 0 0 90)
			(layer "F.SilkS")
			(hide yes)
			(effects
				(font
					(size 1.27 1.27)
				)
			)
		)
		(property "Value" ""
			(at 0 0 90)
			(layer "F.Fab")
			(effects
				(font
					(size 1.27 1.27)
				)
			)
		)
		(duplicate_pad_numbers_are_jumpers no)
		(fp_poly
			(pts
				(xy -0.2794 -0.1016) (xy 0.2794 -0.1016) (xy 0.2794 0.9906) (xy -0.2794 0.9906)
			)
			(stroke
				(width 0)
				(type default)
			)
			(fill no)
			(layer "F.CrtYd")
		)
		(pad "1" smd rect
			(at 0 0 90)
			(size 0.508 0.508)
			(layers "F.Cu" "F.Mask" "F.Paste")
			(net "SPI_PCH_MISO")
		)
		(pad "2" smd rect
			(at 0 0.889 90)
			(size 0.508 0.508)
			(layers "F.Cu" "F.Mask" "F.Paste")
			(net "SPI_PCH_TPM_MISO_R")
		)
		(zone
			(layer "F.Cu")
			(hatch none 0.5)
			(connect_pads
				(clearance 0)
			)
			(min_thickness 0.25)
			(keepout
				(tracks allowed)
				(vias not_allowed)
				(pads allowed)
				(copperpour not_allowed)
				(footprints allowed)
			)
			(placement
				(enabled no)
				(sheetname "")
			)
			(fill
				(thermal_gap 0.5)
				(thermal_bridge_width 0.5)
				(island_removal_mode 0)
			)
			(polygon
				(pts
					(xy 407.2001 -62.357) (xy 407.2001 -62.865) (xy 407.5811 -62.865) (xy 407.5811 -62.357)
				)
			)
		)
		(zone
			(layer "F.Cu")
			(hatch none 0.5)
			(connect_pads
				(clearance 0)
			)
			(min_thickness 0.25)
			(keepout
				(tracks not_allowed)
				(vias allowed)
				(pads allowed)
				(copperpour not_allowed)
				(footprints allowed)
			)
			(placement
				(enabled no)
				(sheetname "")
			)
			(fill
				(thermal_gap 0.5)
				(thermal_bridge_width 0.5)
				(island_removal_mode 0)
			)
			(polygon
				(pts
					(xy 407.5811 -62.357) (xy 407.5811 -62.865) (xy 407.2001 -62.865) (xy 407.2001 -62.357)
				)
			)
		)
	)
	(footprint ""
		(layer "F.Cu")
		(at 389.0645 -80.6196 -90)
		(property "Reference" "C7D5"
			(at 0 0 270)
			(layer "F.SilkS")
			(hide yes)
			(effects
				(font
					(size 1.27 1.27)
				)
			)
		)
		(property "Value" ""
			(at 0 0 270)
			(layer "F.Fab")
			(effects
				(font
					(size 1.27 1.27)
				)
			)
		)
		(duplicate_pad_numbers_are_jumpers no)
		(fp_poly
			(pts
				(xy 0.3048 -0.1016) (xy 0.3048 0.9906) (xy -0.3048 0.9906) (xy -0.3048 -0.1016)
			)
			(stroke
				(width 0)
				(type default)
			)
			(fill no)
			(layer "F.CrtYd")
		)
		(fp_line
			(start -0.3048 0.9906)
			(end 0.3048 0.9906)
			(stroke
				(width 0.1)
				(type default)
			)
			(layer "F.Fab")
		)
		(fp_line
			(start 0.3048 0.9906)
			(end 0.3048 -0.1016)
			(stroke
				(width 0.1)
				(type default)
			)
			(layer "F.Fab")
		)
		(fp_line
			(start -0.3048 -0.1016)
			(end -0.3048 0.9906)
			(stroke
				(width 0.1)
				(type default)
			)
			(layer "F.Fab")
		)
		(fp_line
			(start 0.3048 -0.1016)
			(end -0.3048 -0.1016)
			(stroke
				(width 0.1)
				(type default)
			)
			(layer "F.Fab")
		)
		(pad "1" smd rect
			(at 0 0 270)
			(size 0.508 0.508)
			(layers "F.Cu" "F.Mask" "F.Paste")
			(net "P0V7_GTL2104_VREF_0")
		)
		(pad "2" smd rect
			(at 0 0.889 270)
			(size 0.508 0.508)
			(layers "F.Cu" "F.Mask" "F.Paste")
			(net "GND")
		)
		(zone
			(layer "F.Cu")
			(hatch none 0.5)
			(connect_pads
				(clearance 0)
			)
			(min_thickness 0.25)
			(keepout
				(tracks not_allowed)
				(vias allowed)
				(pads allowed)
				(copperpour not_allowed)
				(footprints allowed)
			)
			(placement
				(enabled no)
				(sheetname "")
			)
			(fill
				(thermal_gap 0.5)
				(thermal_bridge_width 0.5)
				(island_removal_mode 0)
			)
			(polygon
				(pts
					(xy 388.4295 -80.8736) (xy 388.4295 -80.3656) (xy 388.8105 -80.3656) (xy 388.8105 -80.8736)
				)
			)
		)
		(zone
			(layer "F.Cu")
			(hatch none 0.5)
			(connect_pads
				(clearance 0)
			)
			(min_thickness 0.25)
			(keepout
				(tracks allowed)
				(vias not_allowed)
				(pads allowed)
				(copperpour not_allowed)
				(footprints allowed)
			)
			(placement
				(enabled no)
				(sheetname "")
			)
			(fill
				(thermal_gap 0.5)
				(thermal_bridge_width 0.5)
				(island_removal_mode 0)
			)
			(polygon
				(pts
					(xy 388.8105 -80.8736) (xy 388.8105 -80.3656) (xy 388.4295 -80.3656) (xy 388.4295 -80.8736)
				)
			)
		)
	)
	(footprint ""
		(layer "F.Cu")
		(at 205.0288 -49.6824 90)
		(property "Reference" "R4E17"
			(at 0 0 90)
			(layer "F.SilkS")
			(hide yes)
			(effects
				(font
					(size 1.27 1.27)
				)
			)
		)
		(property "Value" ""
			(at 0 0 90)
			(layer "F.Fab")
			(effects
				(font
					(size 1.27 1.27)
				)
			)
		)
		(duplicate_pad_numbers_are_jumpers no)
		(fp_poly
			(pts
				(xy -0.2794 -0.1016) (xy 0.2794 -0.1016) (xy 0.2794 0.9906) (xy -0.2794 0.9906)
			)
			(stroke
				(width 0)
				(type default)
			)
			(fill no)
			(layer "F.CrtYd")
		)
		(fp_line
			(start 0.2794 -0.1016)
			(end -0.2794 -0.1016)
			(stroke
				(width 0.1)
				(type default)
			)
			(layer "F.Fab")
		)
		(fp_line
			(start -0.2794 -0.1016)
			(end -0.2794 0.9906)
			(stroke
				(width 0.1)
				(type default)
			)
			(layer "F.Fab")
		)
		(fp_line
			(start 0.2794 0.9906)
			(end 0.2794 -0.1016)
			(stroke
				(width 0.1)
				(type default)
			)
			(layer "F.Fab")
		)
		(fp_line
			(start -0.2794 0.9906)
			(end 0.2794 0.9906)
			(stroke
				(width 0.1)
				(type default)
			)
			(layer "F.Fab")
		)
		(pad "1" smd rect
			(at 0 0 90)
			(size 0.508 0.508)
			(layers "F.Cu" "F.Mask" "F.Paste")
			(net "VSENSE_PVCCIN_CPU0_N")
		)
		(pad "2" smd rect
			(at 0 0.889 90)
			(size 0.508 0.508)
			(layers "F.Cu" "F.Mask" "F.Paste")
			(net "VSENSE_PVCCIN_CPU0_SKT_VRTN")
		)
		(zone
			(layer "F.Cu")
			(hatch none 0.5)
			(connect_pads
				(clearance 0)
			)
			(min_thickness 0.25)
			(keepout
				(tracks allowed)
				(vias not_allowed)
				(pads allowed)
				(copperpour not_allowed)
				(footprints allowed)
			)
			(placement
				(enabled no)
				(sheetname "")
			)
			(fill
				(thermal_gap 0.5)
				(thermal_bridge_width 0.5)
				(island_removal_mode 0)
			)
			(polygon
				(pts
					(xy 205.2828 -49.4284) (xy 205.2828 -49.9364) (xy 205.6638 -49.9364) (xy 205.6638 -49.4284)
				)
			)
		)
		(zone
			(layer "F.Cu")
			(hatch none 0.5)
			(connect_pads
				(clearance 0)
			)
			(min_thickness 0.25)
			(keepout
				(tracks not_allowed)
				(vias allowed)
				(pads allowed)
				(copperpour not_allowed)
				(footprints allowed)
			)
			(placement
				(enabled no)
				(sheetname "")
			)
			(fill
				(thermal_gap 0.5)
				(thermal_bridge_width 0.5)
				(island_removal_mode 0)
			)
			(polygon
				(pts
					(xy 205.6638 -49.4284) (xy 205.6638 -49.9364) (xy 205.2828 -49.9364) (xy 205.2828 -49.4284)
				)
			)
		)
	)
)
